(kicad_pcb
	(version 20260206)
	(generator "pcbnew")
	(generator_version "10.0")
	(general
		(thickness 1.6)
		(legacy_teardrops no)
	)
	(paper "A4")
	(title_block
		(title "timecard-production-celestica-r4006 — R4006-B0001-02_R01.brd")
		(comment 1 "Time Appliance Project (Time Card) / footprints 105-111 of 1113")
	)
	(layers
		(0 "F.Cu" signal "TOP")
		(4 "In1.Cu" signal "L02_GND1")
		(6 "In2.Cu" signal "L03_SIG1")
		(8 "In3.Cu" signal "L04_GND2")
		(10 "In4.Cu" signal "L05_VCC1")
		(12 "In5.Cu" signal "L06_VCC2")
		(14 "In6.Cu" signal "L07_GND3")
		(16 "In7.Cu" signal "L08_SIG2")
		(18 "In8.Cu" signal "L09_GND4")
		(2 "B.Cu" signal "BOTTOM")
		(9 "F.Adhes" user "F.Adhesive")
		(11 "B.Adhes" user "B.Adhesive")
		(13 "F.Paste" user "Package Geometry/Pastemask Top")
		(15 "B.Paste" user "Package Geometry/Pastemask Bottom")
		(5 "F.SilkS" user "Ref Des/Silkscreen Top")
		(7 "B.SilkS" user "Ref Des/Silkscreen Bottom")
		(1 "F.Mask" user "Board Geometry/Soldermask Top")
		(3 "B.Mask" user "Board Geometry/Soldermask Bottom")
		(17 "Dwgs.User" user "User.Drawings")
		(19 "Cmts.User" user "User.Comments")
		(21 "Eco1.User" user "User.Eco1")
		(23 "Eco2.User" user "User.Eco2")
		(25 "Edge.Cuts" user "Board Geometry/Outline")
		(27 "Margin" user)
		(31 "F.CrtYd" user "Package Geometry/Place Bound Top")
		(29 "B.CrtYd" user "Package Geometry/Place Bound Bottom")
		(35 "F.Fab" user "Ref Des/Assembly Top")
		(33 "B.Fab" user "Ref Des/Assembly Bottom")
	)
	(footprint ""
		(layer "F.Cu")
		(at 162.56 -24.511 180)
		(property "Reference" "R410"
			(at -0.508 -1.56337 0)
			(unlocked yes)
			(layer "F.SilkS")
			(effects
				(font
					(size 0.7874 0.5842)
					(thickness 0.1524)
				)
			)
		)
		(property "Value" "VAL*"
			(at 0.02032 2.13233 180)
			(unlocked yes)
			(layer "F.Fab")
			(hide yes)
			(effects
				(font
					(size 0.7874 0.5842)
					(thickness 0.1524)
				)
			)
		)
		(property "Tolerance" "TOL*"
			(at 0.044704 3.05435 180)
			(unlocked yes)
			(layer "Cmts.User")
			(hide yes)
			(effects
				(font
					(size 0.7874 0.5842)
					(thickness 0.1524)
				)
			)
		)
		(property "User Part Number" "PARTNUM*"
			(at 0.02032 4.024884 180)
			(unlocked yes)
			(layer "Cmts.User")
			(hide yes)
			(effects
				(font
					(size 0.7874 0.5842)
					(thickness 0.1524)
				)
			)
		)
		(property "Device Type" "RESISTOR-G155-14701-01,4.7KOHMA"
			(at 0.008382 1.210564 180)
			(unlocked yes)
			(layer "F.Fab")
			(hide yes)
			(effects
				(font
					(size 0.7874 0.5842)
					(thickness 0.1524)
				)
			)
		)
		(duplicate_pad_numbers_are_jumpers no)
		(fp_line
			(start 1.143 0.5588)
			(end 1.143 -0.5588)
			(stroke
				(width 0.1)
				(type default)
			)
			(layer "F.SilkS")
		)
		(fp_line
			(start 1.143 -0.5588)
			(end -1.143 -0.5588)
			(stroke
				(width 0.1)
				(type default)
			)
			(layer "F.SilkS")
		)
		(fp_line
			(start -1.143 0.5588)
			(end 1.143 0.5588)
			(stroke
				(width 0.1)
				(type default)
			)
			(layer "F.SilkS")
		)
		(fp_line
			(start -1.143 -0.5588)
			(end -1.143 0.5588)
			(stroke
				(width 0.1)
				(type default)
			)
			(layer "F.SilkS")
		)
		(fp_rect
			(start 1.143 0.5588)
			(end -1.143 -0.5588)
			(stroke
				(width 0)
				(type default)
			)
			(fill no)
			(layer "F.CrtYd")
		)
		(fp_line
			(start 0.508 0.3048)
			(end 0.508 -0.3048)
			(stroke
				(width 0.1)
				(type default)
			)
			(layer "F.Fab")
		)
		(fp_line
			(start 0.508 -0.3048)
			(end -0.508 -0.3048)
			(stroke
				(width 0.1)
				(type default)
			)
			(layer "F.Fab")
		)
		(fp_line
			(start -0.508 0.3048)
			(end 0.508 0.3048)
			(stroke
				(width 0.1)
				(type default)
			)
			(layer "F.Fab")
		)
		(fp_line
			(start -0.508 -0.3048)
			(end -0.508 0.3048)
			(stroke
				(width 0.1)
				(type default)
			)
			(layer "F.Fab")
		)
		(pad "1" smd rect
			(at -0.5334 0 180)
			(size 0.7112 0.6096)
			(layers "F.Cu" "F.Mask" "F.Paste")
			(net "XP3R3V_FPGA")
		)
		(pad "2" smd rect
			(at 0.5334 0 180)
			(size 0.7112 0.6096)
			(layers "F.Cu" "F.Mask" "F.Paste")
			(net "UNNAMED_6_LM75BDPTSSOP8_I81_A2")
		)
		(zone
			(layer "F.Cu")
			(hatch none 0.5)
			(connect_pads
				(clearance 0)
			)
			(min_thickness 0.25)
			(keepout
				(tracks allowed)
				(vias not_allowed)
				(pads allowed)
				(copperpour not_allowed)
				(footprints allowed)
			)
			(placement
				(enabled no)
				(sheetname "")
			)
			(fill
				(thermal_gap 0.5)
				(thermal_bridge_width 0.5)
				(island_removal_mode 0)
			)
			(polygon
				(pts
					(xy 162.4838 -24.8158) (xy 162.4838 -24.2062) (xy 162.6362 -24.2062) (xy 162.6362 -24.8158)
				)
			)
		)
		(zone
			(layer "F.Cu")
			(hatch none 0.5)
			(connect_pads
				(clearance 0)
			)
			(min_thickness 0.25)
			(keepout
				(tracks not_allowed)
				(vias allowed)
				(pads allowed)
				(copperpour not_allowed)
				(footprints allowed)
			)
			(placement
				(enabled no)
				(sheetname "")
			)
			(fill
				(thermal_gap 0.5)
				(thermal_bridge_width 0.5)
				(island_removal_mode 0)
			)
			(polygon
				(pts
					(xy 162.4838 -24.8158) (xy 162.4838 -24.2062) (xy 162.6362 -24.2062) (xy 162.6362 -24.8158)
				)
			)
		)
	)
	(footprint ""
		(layer "F.Cu")
		(at 153.924 -59.0296 180)
		(property "Reference" "L17"
			(at 0 1.51003 0)
			(unlocked yes)
			(layer "F.SilkS")
			(effects
				(font
					(size 0.7874 0.5842)
					(thickness 0.1524)
				)
			)
		)
		(property "Value" "VAL*"
			(at 0.014732 2.526538 180)
			(unlocked yes)
			(layer "F.Fab")
			(hide yes)
			(effects
				(font
					(size 0.7874 0.5842)
					(thickness 0.000001)
				)
			)
		)
		(property "Tolerance" "TOL*"
			(at 0.014732 3.503676 180)
			(unlocked yes)
			(layer "Cmts.User")
			(hide yes)
			(effects
				(font
					(size 0.7874 0.5842)
					(thickness 0.000001)
				)
			)
		)
		(property "User Part Number" "PARTNUM*"
			(at 0.02794 4.480814 180)
			(unlocked yes)
			(layer "Cmts.User")
			(hide yes)
			(effects
				(font
					(size 0.7874 0.5842)
					(thickness 0.000001)
				)
			)
		)
		(property "Device Type" "FERRITEBEAD-G191-10097-01,600OA"
			(at 0.014732 1.600708 180)
			(unlocked yes)
			(layer "F.Fab")
			(hide yes)
			(effects
				(font
					(size 0.7874 0.5842)
					(thickness 0.000001)
				)
			)
		)
		(duplicate_pad_numbers_are_jumpers no)
		(fp_line
			(start 1.3208 0.7112)
			(end -1.3208 0.7112)
			(stroke
				(width 0.1)
				(type default)
			)
			(layer "F.SilkS")
		)
		(fp_line
			(start 1.3208 -0.7112)
			(end 1.3208 0.7112)
			(stroke
				(width 0.1)
				(type default)
			)
			(layer "F.SilkS")
		)
		(fp_line
			(start -1.3208 0.7112)
			(end -1.3208 -0.7112)
			(stroke
				(width 0.1)
				(type default)
			)
			(layer "F.SilkS")
		)
		(fp_line
			(start -1.3208 -0.7112)
			(end 1.3208 -0.7112)
			(stroke
				(width 0.1)
				(type default)
			)
			(layer "F.SilkS")
		)
		(fp_rect
			(start -1.3208 0.7112)
			(end 1.3208 -0.7112)
			(stroke
				(width 0)
				(type default)
			)
			(fill no)
			(layer "F.CrtYd")
		)
		(fp_line
			(start 0.8128 0.4572)
			(end -0.8128 0.4572)
			(stroke
				(width 0.1)
				(type default)
			)
			(layer "F.Fab")
		)
		(fp_line
			(start 0.8128 -0.4572)
			(end 0.8128 0.4572)
			(stroke
				(width 0.1)
				(type default)
			)
			(layer "F.Fab")
		)
		(fp_line
			(start -0.8128 0.4572)
			(end -0.8128 -0.4572)
			(stroke
				(width 0.1)
				(type default)
			)
			(layer "F.Fab")
		)
		(fp_line
			(start -0.8128 -0.4572)
			(end 0.8128 -0.4572)
			(stroke
				(width 0.1)
				(type default)
			)
			(layer "F.Fab")
		)
		(pad "1" smd rect
			(at -0.6858 0 180)
			(size 0.762 0.8636)
			(layers "F.Cu" "F.Mask" "F.Paste")
			(net "XP3R3V_FPGA")
		)
		(pad "2" smd rect
			(at 0.6858 0 180)
			(size 0.762 0.8636)
			(layers "F.Cu" "F.Mask" "F.Paste")
			(net "VDD3V3_SHT31A")
		)
		(zone
			(layer "F.Cu")
			(hatch none 0.5)
			(connect_pads
				(clearance 0)
			)
			(min_thickness 0.25)
			(keepout
				(tracks allowed)
				(vias not_allowed)
				(pads allowed)
				(copperpour not_allowed)
				(footprints allowed)
			)
			(placement
				(enabled no)
				(sheetname "")
			)
			(fill
				(thermal_gap 0.5)
				(thermal_bridge_width 0.5)
				(island_removal_mode 0)
			)
			(polygon
				(pts
					(xy 154.0764 -59.4868) (xy 153.7716 -59.4868) (xy 153.7716 -58.5724) (xy 154.0764 -58.5724)
				)
			)
		)
		(zone
			(layer "F.Cu")
			(hatch none 0.5)
			(connect_pads
				(clearance 0)
			)
			(min_thickness 0.25)
			(keepout
				(tracks not_allowed)
				(vias allowed)
				(pads allowed)
				(copperpour not_allowed)
				(footprints allowed)
			)
			(placement
				(enabled no)
				(sheetname "")
			)
			(fill
				(thermal_gap 0.5)
				(thermal_bridge_width 0.5)
				(island_removal_mode 0)
			)
			(polygon
				(pts
					(xy 154.0764 -59.4868) (xy 153.7716 -59.4868) (xy 153.7716 -58.5724) (xy 154.0764 -58.5724)
				)
			)
		)
	)
	(footprint ""
		(layer "F.Cu")
		(at 124.587 -44.831 180)
		(property "Reference" "R211"
			(at -3.048 1.35763 0)
			(unlocked yes)
			(layer "F.SilkS")
			(effects
				(font
					(size 0.7874 0.5842)
					(thickness 0.1524)
				)
			)
		)
		(property "Value" "VAL*"
			(at 0.02032 2.13233 180)
			(unlocked yes)
			(layer "F.Fab")
			(hide yes)
			(effects
				(font
					(size 0.7874 0.5842)
					(thickness 0.1524)
				)
			)
		)
		(property "Device Type" "RESISTOR-G155-11000-01,100OHM,A"
			(at 0.008382 1.210564 180)
			(unlocked yes)
			(layer "F.Fab")
			(hide yes)
			(effects
				(font
					(size 0.7874 0.5842)
					(thickness 0.1524)
				)
			)
		)
		(property "User Part Number" "PARTNUM*"
			(at 0.02032 4.024884 180)
			(unlocked yes)
			(layer "Cmts.User")
			(hide yes)
			(effects
				(font
					(size 0.7874 0.5842)
					(thickness 0.1524)
				)
			)
		)
		(property "Tolerance" "TOL*"
			(at 0.044704 3.05435 180)
			(unlocked yes)
			(layer "Cmts.User")
			(hide yes)
			(effects
				(font
					(size 0.7874 0.5842)
					(thickness 0.1524)
				)
			)
		)
		(duplicate_pad_numbers_are_jumpers no)
		(fp_line
			(start 1.143 0.5588)
			(end 1.143 -0.5588)
			(stroke
				(width 0.1)
				(type default)
			)
			(layer "F.SilkS")
		)
		(fp_line
			(start 1.143 -0.5588)
			(end -1.143 -0.5588)
			(stroke
				(width 0.1)
				(type default)
			)
			(layer "F.SilkS")
		)
		(fp_line
			(start -1.143 0.5588)
			(end 1.143 0.5588)
			(stroke
				(width 0.1)
				(type default)
			)
			(layer "F.SilkS")
		)
		(fp_line
			(start -1.143 -0.5588)
			(end -1.143 0.5588)
			(stroke
				(width 0.1)
				(type default)
			)
			(layer "F.SilkS")
		)
		(fp_rect
			(start 1.143 0.5588)
			(end -1.143 -0.5588)
			(stroke
				(width 0)
				(type default)
			)
			(fill no)
			(layer "F.CrtYd")
		)
		(fp_line
			(start 0.508 0.3048)
			(end 0.508 -0.3048)
			(stroke
				(width 0.1)
				(type default)
			)
			(layer "F.Fab")
		)
		(fp_line
			(start 0.508 -0.3048)
			(end -0.508 -0.3048)
			(stroke
				(width 0.1)
				(type default)
			)
			(layer "F.Fab")
		)
		(fp_line
			(start -0.508 0.3048)
			(end 0.508 0.3048)
			(stroke
				(width 0.1)
				(type default)
			)
			(layer "F.Fab")
		)
		(fp_line
			(start -0.508 -0.3048)
			(end -0.508 0.3048)
			(stroke
				(width 0.1)
				(type default)
			)
			(layer "F.Fab")
		)
		(pad "1" smd rect
			(at -0.5334 0 180)
			(size 0.7112 0.6096)
			(layers "F.Cu" "F.Mask" "F.Paste")
			(net "XP3R3V_FPGA")
		)
		(pad "2" smd rect
			(at 0.5334 0 180)
			(size 0.7112 0.6096)
			(layers "F.Cu" "F.Mask" "F.Paste")
			(net "FPGA_M0")
		)
		(zone
			(layer "F.Cu")
			(hatch none 0.5)
			(connect_pads
				(clearance 0)
			)
			(min_thickness 0.25)
			(keepout
				(tracks allowed)
				(vias not_allowed)
				(pads allowed)
				(copperpour not_allowed)
				(footprints allowed)
			)
			(placement
				(enabled no)
				(sheetname "")
			)
			(fill
				(thermal_gap 0.5)
				(thermal_bridge_width 0.5)
				(island_removal_mode 0)
			)
			(polygon
				(pts
					(xy 124.5108 -45.1358) (xy 124.5108 -44.5262) (xy 124.6632 -44.5262) (xy 124.6632 -45.1358)
				)
			)
		)
	)
	(footprint ""
		(layer "F.Cu")
		(at 44.069 -130.429)
		(property "Reference" "SP64"
			(at 0 0 0)
			(layer "F.SilkS")
			(hide yes)
			(effects
				(font
					(size 1.27 1.27)
				)
			)
		)
		(property "Value" ""
			(at 0 0 0)
			(layer "F.Fab")
			(effects
				(font
					(size 1.27 1.27)
				)
			)
		)
		(duplicate_pad_numbers_are_jumpers no)
	)
	(footprint ""
		(layer "F.Cu")
		(at 131.6482 -65.8368 180)
		(property "Reference" "C197"
			(at -0.635 -4.10337 0)
			(unlocked yes)
			(layer "F.SilkS")
			(effects
				(font
					(size 0.7874 0.5842)
					(thickness 0.1524)
				)
			)
		)
		(property "Value" "VAL*"
			(at 0.0762 2.067306 180)
			(unlocked yes)
			(layer "F.Fab")
			(hide yes)
			(effects
				(font
					(size 0.7874 0.5842)
					(thickness 0.1524)
				)
			)
		)
		(property "Device Type" "CAPACITOR-G105-0B104-EK,0.1UF,A"
			(at 0.0508 1.127506 180)
			(unlocked yes)
			(layer "F.Fab")
			(hide yes)
			(effects
				(font
					(size 0.7874 0.5842)
					(thickness 0.1524)
				)
			)
		)
		(property "User Part Number" "PARTNUM*"
			(at 0.1016 4.023106 180)
			(unlocked yes)
			(layer "Cmts.User")
			(hide yes)
			(effects
				(font
					(size 0.7874 0.5842)
					(thickness 0.1524)
				)
			)
		)
		(property "Tolerance" "TOL*"
			(at 0.0762 3.032506 180)
			(unlocked yes)
			(layer "Cmts.User")
			(hide yes)
			(effects
				(font
					(size 0.7874 0.5842)
					(thickness 0.1524)
				)
			)
		)
		(duplicate_pad_numbers_are_jumpers no)
		(fp_line
			(start 1.143 0.5588)
			(end 1.143 -0.5588)
			(stroke
				(width 0.1)
				(type default)
			)
			(layer "F.SilkS")
		)
		(fp_line
			(start 1.143 -0.5588)
			(end -1.143 -0.5588)
			(stroke
				(width 0.1)
				(type default)
			)
			(layer "F.SilkS")
		)
		(fp_line
			(start -1.143 0.5588)
			(end 1.143 0.5588)
			(stroke
				(width 0.1)
				(type default)
			)
			(layer "F.SilkS")
		)
		(fp_line
			(start -1.143 -0.5588)
			(end -1.143 0.5588)
			(stroke
				(width 0.1)
				(type default)
			)
			(layer "F.SilkS")
		)
		(fp_rect
			(start -1.143 0.5588)
			(end 1.143 -0.5588)
			(stroke
				(width 0)
				(type default)
			)
			(fill no)
			(layer "F.CrtYd")
		)
		(fp_line
			(start 0.508 0.3048)
			(end 0.508 -0.3048)
			(stroke
				(width 0.1)
				(type default)
			)
			(layer "F.Fab")
		)
		(fp_line
			(start 0.508 -0.3048)
			(end -0.508 -0.3048)
			(stroke
				(width 0.1)
				(type default)
			)
			(layer "F.Fab")
		)
		(fp_line
			(start -0.508 0.3048)
			(end 0.508 0.3048)
			(stroke
				(width 0.1)
				(type default)
			)
			(layer "F.Fab")
		)
		(fp_line
			(start -0.508 -0.3048)
			(end -0.508 0.3048)
			(stroke
				(width 0.1)
				(type default)
			)
			(layer "F.Fab")
		)
		(pad "1" smd rect
			(at -0.5334 0 180)
			(size 0.7112 0.6096)
			(layers "F.Cu" "F.Mask" "F.Paste")
			(net "XP1R8V_FPGA")
		)
		(pad "2" smd rect
			(at 0.5334 0 180)
			(size 0.7112 0.6096)
			(layers "F.Cu" "F.Mask" "F.Paste")
			(net "SG")
		)
		(zone
			(layer "F.Cu")
			(hatch none 0.5)
			(connect_pads
				(clearance 0)
			)
			(min_thickness 0.25)
			(keepout
				(tracks allowed)
				(vias not_allowed)
				(pads allowed)
				(copperpour not_allowed)
				(footprints allowed)
			)
			(placement
				(enabled no)
				(sheetname "")
			)
			(fill
				(thermal_gap 0.5)
				(thermal_bridge_width 0.5)
				(island_removal_mode 0)
			)
			(polygon
				(pts
					(xy 131.7244 -66.1416) (xy 131.572 -66.1416) (xy 131.572 -65.532) (xy 131.7244 -65.532)
				)
			)
		)
	)
	(footprint ""
		(layer "F.Cu")
		(at 103.632 -83.058)
		(property "Reference" "TP13"
			(at -0.7112 -1.35763 0)
			(unlocked yes)
			(layer "F.SilkS")
			(effects
				(font
					(size 0.7874 0.5842)
					(thickness 0.1524)
				)
				(justify left)
			)
		)
		(property "Value" ""
			(at 0 0 0)
			(layer "F.Fab")
			(effects
				(font
					(size 1.27 1.27)
				)
			)
		)
		(property "Device Type" "TP_PIONT-TP010CT020B030_PTH-TPA"
			(at -1.341882 0.996696 0)
			(unlocked yes)
			(layer "F.Fab")
			(hide yes)
			(effects
				(font
					(size 0.7874 0.5842)
					(thickness 0.000001)
				)
				(justify left)
			)
		)
		(duplicate_pad_numbers_are_jumpers no)
		(fp_poly
			(pts
				(arc
					(start 0.889 0)
					(mid -0.889 0)
					(end 0.889 0)
				)
			)
			(stroke
				(width 0)
				(type default)
			)
			(fill no)
			(layer "B.CrtYd")
		)
		(fp_poly
			(pts
				(arc
					(start 0.889 0)
					(mid -0.889 0)
					(end 0.889 0)
				)
			)
			(stroke
				(width 0)
				(type default)
			)
			(fill no)
			(layer "F.CrtYd")
		)
		(pad "1" thru_hole circle
			(at 0 0)
			(size 0.508 0.508)
			(drill 0.254)
			(layers "*.Cu" "*.Mask")
			(remove_unused_layers no)
			(net "MUX2_SEL")
			(clearance 0.1016)
			(padstack
				(mode front_inner_back)
				(layer "Inner"
					(shape circle)
					(size 0.508 0.508)
					(clearance 0.1016)
				)
				(layer "B.Cu"
					(shape circle)
					(size 0.762 0.762)
					(clearance -0.0254)
				)
			)
		)
	)
	(footprint ""
		(layer "F.Cu")
		(at 124.079 -89.535 90)
		(property "Reference" "R113"
			(at -3.429 0.16637 90)
			(unlocked yes)
			(layer "F.SilkS")
			(effects
				(font
					(size 0.7874 0.5842)
					(thickness 0.1524)
				)
			)
		)
		(property "Value" "VAL*"
			(at 0.02032 2.13233 90)
			(unlocked yes)
			(layer "F.Fab")
			(hide yes)
			(effects
				(font
					(size 0.7874 0.5842)
					(thickness 0.1524)
				)
			)
		)
		(property "Tolerance" "TOL*"
			(at 0.044704 3.05435 90)
			(unlocked yes)
			(layer "Cmts.User")
			(hide yes)
			(effects
				(font
					(size 0.7874 0.5842)
					(thickness 0.1524)
				)
			)
		)
		(property "User Part Number" "PARTNUM*"
			(at 0.02032 4.024884 90)
			(unlocked yes)
			(layer "Cmts.User")
			(hide yes)
			(effects
				(font
					(size 0.7874 0.5842)
					(thickness 0.1524)
				)
			)
		)
		(property "Device Type" "RESISTOR-G155-133R0-01,33OHM,1%"
			(at 0.008382 1.210564 90)
			(unlocked yes)
			(layer "F.Fab")
			(hide yes)
			(effects
				(font
					(size 0.7874 0.5842)
					(thickness 0.1524)
				)
			)
		)
		(duplicate_pad_numbers_are_jumpers no)
		(fp_line
			(start 1.143 -0.5588)
			(end -1.143 -0.5588)
			(stroke
				(width 0.1)
				(type default)
			)
			(layer "F.SilkS")
		)
		(fp_line
			(start -1.143 -0.5588)
			(end -1.143 0.5588)
			(stroke
				(width 0.1)
				(type default)
			)
			(layer "F.SilkS")
		)
		(fp_line
			(start 1.143 0.5588)
			(end 1.143 -0.5588)
			(stroke
				(width 0.1)
				(type default)
			)
			(layer "F.SilkS")
		)
		(fp_line
			(start -1.143 0.5588)
			(end 1.143 0.5588)
			(stroke
				(width 0.1)
				(type default)
			)
			(layer "F.SilkS")
		)
		(fp_rect
			(start 1.143 -0.5588)
			(end -1.143 0.5588)
			(stroke
				(width 0)
				(type default)
			)
			(fill no)
			(layer "F.CrtYd")
		)
		(fp_line
			(start 0.508 -0.3048)
			(end -0.508 -0.3048)
			(stroke
				(width 0.1)
				(type default)
			)
			(layer "F.Fab")
		)
		(fp_line
			(start -0.508 -0.3048)
			(end -0.508 0.3048)
			(stroke
				(width 0.1)
				(type default)
			)
			(layer "F.Fab")
		)
		(fp_line
			(start 0.508 0.3048)
			(end 0.508 -0.3048)
			(stroke
				(width 0.1)
				(type default)
			)
			(layer "F.Fab")
		)
		(fp_line
			(start -0.508 0.3048)
			(end 0.508 0.3048)
			(stroke
				(width 0.1)
				(type default)
			)
			(layer "F.Fab")
		)
		(pad "1" smd rect
			(at -0.5334 0 90)
			(size 0.7112 0.6096)
			(layers "F.Cu" "F.Mask" "F.Paste")
			(net "DBG_UART_GPS_RXD")
		)
		(pad "2" smd rect
			(at 0.5334 0 90)
			(size 0.7112 0.6096)
			(layers "F.Cu" "F.Mask" "F.Paste")
			(net "GPS_UART_RXD")
		)
		(zone
			(layer "F.Cu")
			(hatch none 0.5)
			(connect_pads
				(clearance 0)
			)
			(min_thickness 0.25)
			(keepout
				(tracks allowed)
				(vias not_allowed)
				(pads allowed)
				(copperpour not_allowed)
				(footprints allowed)
			)
			(placement
				(enabled no)
				(sheetname "")
			)
			(fill
				(thermal_gap 0.5)
				(thermal_bridge_width 0.5)
				(island_removal_mode 0)
			)
			(polygon
				(pts
					(xy 123.7742 -89.6112) (xy 123.7742 -89.4588) (xy 124.3838 -89.4588) (xy 124.3838 -89.6112)
				)
			)
		)
	)
)
